(kicad_pcb
	(version 20241229)
	(generator "pcbnew")
	(generator_version "9.0")
	(general
		(thickness 1.62)
		(legacy_teardrops no)
	)
	(paper "A3")
	(title_block
		(title "COM Express 7 Baseboard")
		(date "2025-02-04")
		(rev "1.1.2")
		(company "Antmicro Ltd")
		(comment 1 "www.antmicro.com")
		(comment 9 "footprint 244 of 802 (U43), pads 1-39 of 144")
	)
	(layers
		(0 "F.Cu" signal)
		(4 "In1.Cu" signal)
		(6 "In2.Cu" signal)
		(8 "In3.Cu" signal)
		(10 "In4.Cu" signal)
		(12 "In5.Cu" signal)
		(14 "In6.Cu" signal)
		(2 "B.Cu" signal)
		(9 "F.Adhes" user "F.Adhesive")
		(11 "B.Adhes" user "B.Adhesive")
		(13 "F.Paste" user)
		(15 "B.Paste" user)
		(5 "F.SilkS" user "F.Silkscreen")
		(7 "B.SilkS" user "B.Silkscreen")
		(1 "F.Mask" user)
		(3 "B.Mask" user)
		(17 "Dwgs.User" user "User.Drawings")
		(19 "Cmts.User" user "User.Comments")
		(21 "Eco1.User" user "User.Eco1")
		(23 "Eco2.User" user "User.Eco2")
		(25 "Edge.Cuts" user)
		(27 "Margin" user)
		(31 "F.CrtYd" user "F.Courtyard")
		(29 "B.CrtYd" user "B.Courtyard")
		(35 "F.Fab" user)
		(33 "B.Fab" user)
	)
	(footprint "antmicro-footprints:BGA-144_12x12_13.05x13.05mm_P1.0mm"
		(layer "F.Cu")
		(at 150.95 137.36 -90)
		(property "Reference" "U43"
			(at 7.9 4.65 180)
			(layer "F.SilkS")
			(effects
				(font
					(size 0.7 0.7)
					(thickness 0.15)
				)
				(justify right bottom)
			)
		)
		(property "Value" "TLK10232CTR"
			(at 0 7.525 90)
			(layer "F.Fab")
			(effects
				(font
					(size 0.7 0.7)
					(thickness 0.15)
				)
				(justify right bottom)
			)
		)
		(property "Datasheet" "https://www.ti.com/lit/ds/symlink/tlk10232.pdf?ts=1712150848075&ref_url=https%253A%252F%252Fwww.mouser.pl%252F"
			(at 0 0 270)
			(layer "F.Fab")
			(hide yes)
			(effects
				(font
					(size 1.27 1.27)
					(thickness 0.15)
				)
			)
		)
		(property "Author" "Antmicro"
			(at 13.59 288.31 0)
			(layer "F.Fab")
			(hide yes)
			(effects
				(font
					(size 1 1)
					(thickness 0.15)
				)
			)
		)
		(property "License" "Apache-2.0"
			(at 13.59 288.31 0)
			(layer "F.Fab")
			(hide yes)
			(effects
				(font
					(size 1 1)
					(thickness 0.15)
				)
			)
		)
		(property "MPN" "TLK10232CTR"
			(at 13.59 288.31 0)
			(layer "F.Fab")
			(hide yes)
			(effects
				(font
					(size 1 1)
					(thickness 0.15)
				)
			)
		)
		(property "Manufacturer" "Texas Instruments"
			(at 13.59 288.31 0)
			(layer "F.Fab")
			(hide yes)
			(effects
				(font
					(size 1 1)
					(thickness 0.15)
				)
			)
		)
		(sheetname "KR to SFI #1")
		(sheetfile "kr_sfi.kicad_sch")
		(attr smd)
		(pad "A1" smd circle
			(at -5.5 -5.5 270)
			(size 0.5 0.5)
			(layers "F.Cu" "F.Mask" "F.Paste")
			(net 800 "unconnected-(U43A-INA1+-PadA1)")
			(pinfunction "INA1+")
			(pintype "input+no_connect")
			(solder_mask_margin 0.05)
			(teardrops
				(best_length_ratio 0.4)
				(max_length 1)
				(best_width_ratio 0.9)
				(max_width 2)
				(curved_edges yes)
				(filter_ratio 0.9)
				(enabled yes)
				(allow_two_segments yes)
				(prefer_zone_connections yes)
			)
		)
		(pad "A2" smd circle
			(at -4.5 -5.5 270)
			(size 0.5 0.5)
			(layers "F.Cu" "F.Mask" "F.Paste")
			(net 1 "GND")
			(pinfunction "GND")
			(pintype "passive")
			(solder_mask_margin 0.05)
			(teardrops
				(best_length_ratio 0.4)
				(max_length 1)
				(best_width_ratio 0.9)
				(max_width 2)
				(curved_edges yes)
				(filter_ratio 0.9)
				(enabled yes)
				(allow_two_segments yes)
				(prefer_zone_connections yes)
			)
		)
		(pad "A3" smd circle
			(at -3.5 -5.5 270)
			(size 0.5 0.5)
			(layers "F.Cu" "F.Mask" "F.Paste")
			(net 801 "unconnected-(U43A-INA0--PadA3)")
			(pinfunction "INA0-")
			(pintype "input+no_connect")
			(solder_mask_margin 0.05)
			(teardrops
				(best_length_ratio 0.4)
				(max_length 1)
				(best_width_ratio 0.9)
				(max_width 2)
				(curved_edges yes)
				(filter_ratio 0.9)
				(enabled yes)
				(allow_two_segments yes)
				(prefer_zone_connections yes)
			)
		)
		(pad "A4" smd circle
			(at -2.5 -5.5 270)
			(size 0.5 0.5)
			(layers "F.Cu" "F.Mask" "F.Paste")
			(net 802 "unconnected-(U43A-INA0+-PadA4)")
			(pinfunction "INA0+")
			(pintype "input+no_connect")
			(solder_mask_margin 0.05)
			(teardrops
				(best_length_ratio 0.4)
				(max_length 1)
				(best_width_ratio 0.9)
				(max_width 2)
				(curved_edges yes)
				(filter_ratio 0.9)
				(enabled yes)
				(allow_two_segments yes)
				(prefer_zone_connections yes)
			)
		)
		(pad "A5" smd circle
			(at -1.5 -5.5 270)
			(size 0.5 0.5)
			(layers "F.Cu" "F.Mask" "F.Paste")
			(net 1 "GND")
			(pinfunction "GND")
			(pintype "passive")
			(solder_mask_margin 0.05)
			(teardrops
				(best_length_ratio 0.4)
				(max_length 1)
				(best_width_ratio 0.9)
				(max_width 2)
				(curved_edges yes)
				(filter_ratio 0.9)
				(enabled yes)
				(allow_two_segments yes)
				(prefer_zone_connections yes)
			)
		)
		(pad "A6" smd circle
			(at -0.5 -5.5 270)
			(size 0.5 0.5)
			(layers "F.Cu" "F.Mask" "F.Paste")
			(net 803 "unconnected-(U43A-OUTA0+-PadA6)")
			(pinfunction "OUTA0+")
			(pintype "output+no_connect")
			(solder_mask_margin 0.05)
			(teardrops
				(best_length_ratio 0.4)
				(max_length 1)
				(best_width_ratio 0.9)
				(max_width 2)
				(curved_edges yes)
				(filter_ratio 0.9)
				(enabled yes)
				(allow_two_segments yes)
				(prefer_zone_connections yes)
			)
		)
		(pad "A7" smd circle
			(at 0.5 -5.5 270)
			(size 0.5 0.5)
			(layers "F.Cu" "F.Mask" "F.Paste")
			(net 804 "unconnected-(U43A-OUTA0--PadA7)")
			(pinfunction "OUTA0-")
			(pintype "output+no_connect")
			(solder_mask_margin 0.05)
			(teardrops
				(best_length_ratio 0.4)
				(max_length 1)
				(best_width_ratio 0.9)
				(max_width 2)
				(curved_edges yes)
				(filter_ratio 0.9)
				(enabled yes)
				(allow_two_segments yes)
				(prefer_zone_connections yes)
			)
		)
		(pad "A8" smd circle
			(at 1.5 -5.5 270)
			(size 0.5 0.5)
			(layers "F.Cu" "F.Mask" "F.Paste")
			(net 657 "Net-(U43A-~{PDTRXA})")
			(pinfunction "~{PDTRXA}")
			(pintype "input")
			(solder_mask_margin 0.05)
			(teardrops
				(best_length_ratio 0.4)
				(max_length 1)
				(best_width_ratio 0.9)
				(max_width 2)
				(curved_edges yes)
				(filter_ratio 0.9)
				(enabled yes)
				(allow_two_segments yes)
				(prefer_zone_connections yes)
			)
		)
		(pad "A9" smd circle
			(at 2.5 -5.5 270)
			(size 0.5 0.5)
			(layers "F.Cu" "F.Mask" "F.Paste")
			(net 732 "Net-(U43C-CLKOUTB+)")
			(pinfunction "CLKOUTB+")
			(pintype "output")
			(solder_mask_margin 0.05)
			(teardrops
				(best_length_ratio 0.4)
				(max_length 1)
				(best_width_ratio 0.9)
				(max_width 2)
				(curved_edges yes)
				(filter_ratio 0.9)
				(enabled yes)
				(allow_two_segments yes)
				(prefer_zone_connections yes)
			)
		)
		(pad "A10" smd circle
			(at 3.5 -5.5 270)
			(size 0.5 0.5)
			(layers "F.Cu" "F.Mask" "F.Paste")
			(net 733 "Net-(U43C-CLKOUTB-)")
			(pinfunction "CLKOUTB-")
			(pintype "output")
			(solder_mask_margin 0.05)
			(teardrops
				(best_length_ratio 0.4)
				(max_length 1)
				(best_width_ratio 0.9)
				(max_width 2)
				(curved_edges yes)
				(filter_ratio 0.9)
				(enabled yes)
				(allow_two_segments yes)
				(prefer_zone_connections yes)
			)
		)
		(pad "A11" smd circle
			(at 4.5 -5.5 270)
			(size 0.5 0.5)
			(layers "F.Cu" "F.Mask" "F.Paste")
			(net 1 "GND")
			(pinfunction "GND")
			(pintype "power_in")
			(solder_mask_margin 0.05)
			(teardrops
				(best_length_ratio 0.4)
				(max_length 1)
				(best_width_ratio 0.9)
				(max_width 2)
				(curved_edges yes)
				(filter_ratio 0.9)
				(enabled yes)
				(allow_two_segments yes)
				(prefer_zone_connections yes)
			)
		)
		(pad "A12" smd circle
			(at 5.5 -5.5 270)
			(size 0.5 0.5)
			(layers "F.Cu" "F.Mask" "F.Paste")
			(net 114 "/2xSFP+/KR to SFI #1/KR_C.TX-")
			(pinfunction "HSRXA-")
			(pintype "input")
			(solder_mask_margin 0.05)
			(teardrops
				(best_length_ratio 0.4)
				(max_length 1)
				(best_width_ratio 0.9)
				(max_width 2)
				(curved_edges yes)
				(filter_ratio 0.9)
				(enabled yes)
				(allow_two_segments yes)
				(prefer_zone_connections yes)
			)
		)
		(pad "B1" smd circle
			(at -5.5 -4.5 270)
			(size 0.5 0.5)
			(layers "F.Cu" "F.Mask" "F.Paste")
			(net 805 "unconnected-(U43A-INA1--PadB1)")
			(pinfunction "INA1-")
			(pintype "input+no_connect")
			(solder_mask_margin 0.05)
			(teardrops
				(best_length_ratio 0.4)
				(max_length 1)
				(best_width_ratio 0.9)
				(max_width 2)
				(curved_edges yes)
				(filter_ratio 0.9)
				(enabled yes)
				(allow_two_segments yes)
				(prefer_zone_connections yes)
			)
		)
		(pad "B2" smd circle
			(at -4.5 -4.5 270)
			(size 0.5 0.5)
			(layers "F.Cu" "F.Mask" "F.Paste")
			(net 806 "unconnected-(U43A-INA2+-PadB2)")
			(pinfunction "INA2+")
			(pintype "input+no_connect")
			(solder_mask_margin 0.05)
			(teardrops
				(best_length_ratio 0.4)
				(max_length 1)
				(best_width_ratio 0.9)
				(max_width 2)
				(curved_edges yes)
				(filter_ratio 0.9)
				(enabled yes)
				(allow_two_segments yes)
				(prefer_zone_connections yes)
			)
		)
		(pad "B3" smd circle
			(at -3.5 -4.5 270)
			(size 0.5 0.5)
			(layers "F.Cu" "F.Mask" "F.Paste")
			(net 1 "GND")
			(pinfunction "GND")
			(pintype "passive")
			(solder_mask_margin 0.05)
			(teardrops
				(best_length_ratio 0.4)
				(max_length 1)
				(best_width_ratio 0.9)
				(max_width 2)
				(curved_edges yes)
				(filter_ratio 0.9)
				(enabled yes)
				(allow_two_segments yes)
				(prefer_zone_connections yes)
			)
		)
		(pad "B4" smd circle
			(at -2.5 -4.5 270)
			(size 0.5 0.5)
			(layers "F.Cu" "F.Mask" "F.Paste")
			(net 1 "GND")
			(pinfunction "GND")
			(pintype "passive")
			(solder_mask_margin 0.05)
			(teardrops
				(best_length_ratio 0.4)
				(max_length 1)
				(best_width_ratio 0.9)
				(max_width 2)
				(curved_edges yes)
				(filter_ratio 0.9)
				(enabled yes)
				(allow_two_segments yes)
				(prefer_zone_connections yes)
			)
		)
		(pad "B5" smd circle
			(at -1.5 -4.5 270)
			(size 0.5 0.5)
			(layers "F.Cu" "F.Mask" "F.Paste")
			(net 807 "unconnected-(U43A-OUTA1+-PadB5)")
			(pinfunction "OUTA1+")
			(pintype "output+no_connect")
			(solder_mask_margin 0.05)
			(teardrops
				(best_length_ratio 0.4)
				(max_length 1)
				(best_width_ratio 0.9)
				(max_width 2)
				(curved_edges yes)
				(filter_ratio 0.9)
				(enabled yes)
				(allow_two_segments yes)
				(prefer_zone_connections yes)
			)
		)
		(pad "B6" smd circle
			(at -0.5 -4.5 270)
			(size 0.5 0.5)
			(layers "F.Cu" "F.Mask" "F.Paste")
			(net 808 "unconnected-(U43A-OUTA1--PadB6)")
			(pinfunction "OUTA1-")
			(pintype "output+no_connect")
			(solder_mask_margin 0.05)
			(teardrops
				(best_length_ratio 0.4)
				(max_length 1)
				(best_width_ratio 0.9)
				(max_width 2)
				(curved_edges yes)
				(filter_ratio 0.9)
				(enabled yes)
				(allow_two_segments yes)
				(prefer_zone_connections yes)
			)
		)
		(pad "B7" smd circle
			(at 0.5 -4.5 270)
			(size 0.5 0.5)
			(layers "F.Cu" "F.Mask" "F.Paste")
			(net 1 "GND")
			(pinfunction "GND")
			(pintype "passive")
			(solder_mask_margin 0.05)
			(teardrops
				(best_length_ratio 0.4)
				(max_length 1)
				(best_width_ratio 0.9)
				(max_width 2)
				(curved_edges yes)
				(filter_ratio 0.9)
				(enabled yes)
				(allow_two_segments yes)
				(prefer_zone_connections yes)
			)
		)
		(pad "B8" smd circle
			(at 1.5 -4.5 270)
			(size 0.5 0.5)
			(layers "F.Cu" "F.Mask" "F.Paste")
			(net 724 "/2xSFP+/KR to SFI #1/TMS")
			(pinfunction "TMS")
			(pintype "input")
			(solder_mask_margin 0.05)
			(teardrops
				(best_length_ratio 0.4)
				(max_length 1)
				(best_width_ratio 0.9)
				(max_width 2)
				(curved_edges yes)
				(filter_ratio 0.9)
				(enabled yes)
				(allow_two_segments yes)
				(prefer_zone_connections yes)
			)
		)
		(pad "B9" smd circle
			(at 2.5 -4.5 270)
			(size 0.5 0.5)
			(layers "F.Cu" "F.Mask" "F.Paste")
			(net 652 "/2xSFP+/KR to SFI #1/PRBSEN")
			(pinfunction "PRBSEN")
			(pintype "input")
			(solder_mask_margin 0.05)
			(teardrops
				(best_length_ratio 0.4)
				(max_length 1)
				(best_width_ratio 0.9)
				(max_width 2)
				(curved_edges yes)
				(filter_ratio 0.9)
				(enabled yes)
				(allow_two_segments yes)
				(prefer_zone_connections yes)
			)
		)
		(pad "B10" smd circle
			(at 3.5 -4.5 270)
			(size 0.5 0.5)
			(layers "F.Cu" "F.Mask" "F.Paste")
			(net 735 "Net-(U43A-LS_OK_{IN_A})")
			(pinfunction "LS_OK_{IN_A}")
			(pintype "input")
			(solder_mask_margin 0.05)
			(teardrops
				(best_length_ratio 0.4)
				(max_length 1)
				(best_width_ratio 0.9)
				(max_width 2)
				(curved_edges yes)
				(filter_ratio 0.9)
				(enabled yes)
				(allow_two_segments yes)
				(prefer_zone_connections yes)
			)
		)
		(pad "B11" smd circle
			(at 4.5 -4.5 270)
			(size 0.5 0.5)
			(layers "F.Cu" "F.Mask" "F.Paste")
			(net 1 "GND")
			(pinfunction "GND")
			(pintype "passive")
			(solder_mask_margin 0.05)
			(teardrops
				(best_length_ratio 0.4)
				(max_length 1)
				(best_width_ratio 0.9)
				(max_width 2)
				(curved_edges yes)
				(filter_ratio 0.9)
				(enabled yes)
				(allow_two_segments yes)
				(prefer_zone_connections yes)
			)
		)
		(pad "B12" smd circle
			(at 5.5 -4.5 270)
			(size 0.5 0.5)
			(layers "F.Cu" "F.Mask" "F.Paste")
			(net 112 "/2xSFP+/KR to SFI #1/KR_C.TX+")
			(pinfunction "HSRXA+")
			(pintype "input")
			(solder_mask_margin 0.05)
			(teardrops
				(best_length_ratio 0.4)
				(max_length 1)
				(best_width_ratio 0.9)
				(max_width 2)
				(curved_edges yes)
				(filter_ratio 0.9)
				(enabled yes)
				(allow_two_segments yes)
				(prefer_zone_connections yes)
			)
		)
		(pad "C1" smd circle
			(at -5.5 -3.5 270)
			(size 0.5 0.5)
			(layers "F.Cu" "F.Mask" "F.Paste")
			(net 1 "GND")
			(pinfunction "GND")
			(pintype "passive")
			(solder_mask_margin 0.05)
			(teardrops
				(best_length_ratio 0.4)
				(max_length 1)
				(best_width_ratio 0.9)
				(max_width 2)
				(curved_edges yes)
				(filter_ratio 0.9)
				(enabled yes)
				(allow_two_segments yes)
				(prefer_zone_connections yes)
			)
		)
		(pad "C2" smd circle
			(at -4.5 -3.5 270)
			(size 0.5 0.5)
			(layers "F.Cu" "F.Mask" "F.Paste")
			(net 809 "unconnected-(U43A-INA2--PadC2)")
			(pinfunction "INA2-")
			(pintype "input+no_connect")
			(solder_mask_margin 0.05)
			(teardrops
				(best_length_ratio 0.4)
				(max_length 1)
				(best_width_ratio 0.9)
				(max_width 2)
				(curved_edges yes)
				(filter_ratio 0.9)
				(enabled yes)
				(allow_two_segments yes)
				(prefer_zone_connections yes)
			)
		)
		(pad "C3" smd circle
			(at -3.5 -3.5 270)
			(size 0.5 0.5)
			(layers "F.Cu" "F.Mask" "F.Paste")
			(net 78 "+1V8")
			(pinfunction "VDDRA_{LS/HS}")
			(pintype "power_in")
			(solder_mask_margin 0.05)
			(teardrops
				(best_length_ratio 0.4)
				(max_length 1)
				(best_width_ratio 0.9)
				(max_width 2)
				(curved_edges yes)
				(filter_ratio 0.9)
				(enabled yes)
				(allow_two_segments yes)
				(prefer_zone_connections yes)
			)
		)
		(pad "C4" smd circle
			(at -2.5 -3.5 270)
			(size 0.5 0.5)
			(layers "F.Cu" "F.Mask" "F.Paste")
			(net 810 "unconnected-(U43A-OUTA2+-PadC4)")
			(pinfunction "OUTA2+")
			(pintype "output+no_connect")
			(solder_mask_margin 0.05)
			(teardrops
				(best_length_ratio 0.4)
				(max_length 1)
				(best_width_ratio 0.9)
				(max_width 2)
				(curved_edges yes)
				(filter_ratio 0.9)
				(enabled yes)
				(allow_two_segments yes)
				(prefer_zone_connections yes)
			)
		)
		(pad "C5" smd circle
			(at -1.5 -3.5 270)
			(size 0.5 0.5)
			(layers "F.Cu" "F.Mask" "F.Paste")
			(net 811 "unconnected-(U43A-OUTA2--PadC5)")
			(pinfunction "OUTA2-")
			(pintype "output+no_connect")
			(solder_mask_margin 0.05)
			(teardrops
				(best_length_ratio 0.4)
				(max_length 1)
				(best_width_ratio 0.9)
				(max_width 2)
				(curved_edges yes)
				(filter_ratio 0.9)
				(enabled yes)
				(allow_two_segments yes)
				(prefer_zone_connections yes)
			)
		)
		(pad "C6" smd circle
			(at -0.5 -3.5 270)
			(size 0.5 0.5)
			(layers "F.Cu" "F.Mask" "F.Paste")
			(net 1 "GND")
			(pinfunction "GND")
			(pintype "passive")
			(solder_mask_margin 0.05)
			(teardrops
				(best_length_ratio 0.4)
				(max_length 1)
				(best_width_ratio 0.9)
				(max_width 2)
				(curved_edges yes)
				(filter_ratio 0.9)
				(enabled yes)
				(allow_two_segments yes)
				(prefer_zone_connections yes)
			)
		)
		(pad "C7" smd circle
			(at 0.5 -3.5 270)
			(size 0.5 0.5)
			(layers "F.Cu" "F.Mask" "F.Paste")
			(net 74 "+1V0")
			(pinfunction "VDDO0")
			(pintype "power_in")
			(solder_mask_margin 0.05)
			(teardrops
				(best_length_ratio 0.4)
				(max_length 1)
				(best_width_ratio 0.9)
				(max_width 2)
				(curved_edges yes)
				(filter_ratio 0.9)
				(enabled yes)
				(allow_two_segments yes)
				(prefer_zone_connections yes)
			)
		)
		(pad "C8" smd circle
			(at 1.5 -3.5 270)
			(size 0.5 0.5)
			(layers "F.Cu" "F.Mask" "F.Paste")
			(net 722 "/2xSFP+/KR to SFI #1/TDI")
			(pinfunction "TDI")
			(pintype "input")
			(solder_mask_margin 0.05)
			(teardrops
				(best_length_ratio 0.4)
				(max_length 1)
				(best_width_ratio 0.9)
				(max_width 2)
				(curved_edges yes)
				(filter_ratio 0.9)
				(enabled yes)
				(allow_two_segments yes)
				(prefer_zone_connections yes)
			)
		)
		(pad "C9" smd circle
			(at 2.5 -3.5 270)
			(size 0.5 0.5)
			(layers "F.Cu" "F.Mask" "F.Paste")
			(net 730 "Net-(U43C-CLKOUTA+)")
			(pinfunction "CLKOUTA+")
			(pintype "output")
			(solder_mask_margin 0.05)
			(teardrops
				(best_length_ratio 0.4)
				(max_length 1)
				(best_width_ratio 0.9)
				(max_width 2)
				(curved_edges yes)
				(filter_ratio 0.9)
				(enabled yes)
				(allow_two_segments yes)
				(prefer_zone_connections yes)
			)
		)
		(pad "C10" smd circle
			(at 3.5 -3.5 270)
			(size 0.5 0.5)
			(layers "F.Cu" "F.Mask" "F.Paste")
			(net 731 "Net-(U43C-CLKOUTA-)")
			(pinfunction "CLKOUTA-")
			(pintype "output")
			(solder_mask_margin 0.05)
			(teardrops
				(best_length_ratio 0.4)
				(max_length 1)
				(best_width_ratio 0.9)
				(max_width 2)
				(curved_edges yes)
				(filter_ratio 0.9)
				(enabled yes)
				(allow_two_segments yes)
				(prefer_zone_connections yes)
			)
		)
		(pad "C11" smd circle
			(at 4.5 -3.5 270)
			(size 0.5 0.5)
			(layers "F.Cu" "F.Mask" "F.Paste")
			(net 728 "Net-(U43C-AMUXA)")
			(pinfunction "AMUXA")
			(pintype "passive")
			(solder_mask_margin 0.05)
			(teardrops
				(best_length_ratio 0.4)
				(max_length 1)
				(best_width_ratio 0.9)
				(max_width 2)
				(curved_edges yes)
				(filter_ratio 0.9)
				(enabled yes)
				(allow_two_segments yes)
				(prefer_zone_connections yes)
			)
		)
		(pad "C12" smd circle
			(at 5.5 -3.5 270)
			(size 0.5 0.5)
			(layers "F.Cu" "F.Mask" "F.Paste")
			(net 1 "GND")
			(pinfunction "GND")
			(pintype "passive")
			(solder_mask_margin 0.05)
			(teardrops
				(best_length_ratio 0.4)
				(max_length 1)
				(best_width_ratio 0.9)
				(max_width 2)
				(curved_edges yes)
				(filter_ratio 0.9)
				(enabled yes)
				(allow_two_segments yes)
				(prefer_zone_connections yes)
			)
		)
		(pad "D1" smd circle
			(at -5.5 -2.5 270)
			(size 0.5 0.5)
			(layers "F.Cu" "F.Mask" "F.Paste")
			(net 812 "unconnected-(U43A-INA3+-PadD1)")
			(pinfunction "INA3+")
			(pintype "input+no_connect")
			(solder_mask_margin 0.05)
			(teardrops
				(best_length_ratio 0.4)
				(max_length 1)
				(best_width_ratio 0.9)
				(max_width 2)
				(curved_edges yes)
				(filter_ratio 0.9)
				(enabled yes)
				(allow_two_segments yes)
				(prefer_zone_connections yes)
			)
		)
		(pad "D2" smd circle
			(at -4.5 -2.5 270)
			(size 0.5 0.5)
			(layers "F.Cu" "F.Mask" "F.Paste")
			(net 74 "+1V0")
			(pinfunction "VDDA_{LS/HS}")
			(pintype "power_in")
			(solder_mask_margin 0.05)
			(teardrops
				(best_length_ratio 0.4)
				(max_length 1)
				(best_width_ratio 0.9)
				(max_width 2)
				(curved_edges yes)
				(filter_ratio 0.9)
				(enabled yes)
				(allow_two_segments yes)
				(prefer_zone_connections yes)
			)
		)
		(pad "D3" smd circle
			(at -3.5 -2.5 270)
			(size 0.5 0.5)
			(layers "F.Cu" "F.Mask" "F.Paste")
			(net 1 "GND")
			(pinfunction "GND")
			(pintype "passive")
			(solder_mask_margin 0.05)
			(teardrops
				(best_length_ratio 0.4)
				(max_length 1)
				(best_width_ratio 0.9)
				(max_width 2)
				(curved_edges yes)
				(filter_ratio 0.9)
				(enabled yes)
				(allow_two_segments yes)
				(prefer_zone_connections yes)
			)
		)
	)
)
